(kicad_pcb
	(version 20260206)
	(generator "pcbnew")
	(generator_version "10.0")
	(general
		(thickness 1.6)
		(legacy_teardrops no)
	)
	(paper "A4")
	(title_block
		(title "Bryce Canyon_IOM_IOC_16318-2_OCP.brd")
		(comment 1 "Bryce Canyon / footprint 367 of 1605 (U2), pads 346-456 of 456")
	)
	(layers
		(0 "F.Cu" signal "TOP")
		(4 "In1.Cu" signal "L2GND")
		(6 "In2.Cu" signal "L3")
		(8 "In3.Cu" signal "L4VCC")
		(10 "In4.Cu" signal "L5VCC")
		(12 "In5.Cu" signal "L6")
		(14 "In6.Cu" signal "L7GND")
		(2 "B.Cu" signal "BOTTOM")
		(9 "F.Adhes" user "F.Adhesive")
		(11 "B.Adhes" user "B.Adhesive")
		(13 "F.Paste" user "Package Geometry/Pastemask Top")
		(15 "B.Paste" user "Package Geometry/Pastemask Bottom")
		(5 "F.SilkS" user "Ref Des/Silkscreen Top")
		(7 "B.SilkS" user "Ref Des/Silkscreen Bottom")
		(1 "F.Mask" user "Board Geometry/Soldermask Top")
		(3 "B.Mask" user "Board Geometry/Soldermask Bottom")
		(17 "Dwgs.User" user "User.Drawings")
		(19 "Cmts.User" user "User.Comments")
		(21 "Eco1.User" user "User.Eco1")
		(23 "Eco2.User" user "User.Eco2")
		(25 "Edge.Cuts" user "Board Geometry/Outline")
		(27 "Margin" user)
		(31 "F.CrtYd" user "Package Geometry/Place Bound Top")
		(29 "B.CrtYd" user "Package Geometry/Place Bound Bottom")
		(35 "F.Fab" user "Ref Des/Assembly Top")
		(33 "B.Fab" user "Ref Des/Assembly Bottom")
	)
	(footprint ""
		(layer "F.Cu")
		(at 47.69993 -144.999964 -90)
		(property "Reference" "U2"
			(at 0 0 270)
			(layer "F.SilkS")
			(hide yes)
			(effects
				(font
					(size 1.27 1.27)
				)
			)
		)
		(property "Value" "AST2500A2-GP-GP-U"
			(at -17.0307 -8.584692 270)
			(unlocked yes)
			(layer "F.Fab")
			(hide yes)
			(effects
				(font
					(size 1.016 1.016)
					(thickness 0.1524)
				)
			)
		)
		(property "Device Type" "BGA456D19H58"
			(at -17.0307 -10.108692 270)
			(unlocked yes)
			(layer "F.Fab")
			(hide yes)
			(effects
				(font
					(size 1.016 1.016)
					(thickness 0.1524)
				)
			)
		)
		(duplicate_pad_numbers_are_jumpers no)
		(pad "R22" smd circle
			(at 8.400034 2.800096 270)
			(size 0.3556 0.3556)
			(layers "F.Cu" "F.Mask" "F.Paste")
			(net "BMC_GPIOY0")
		)
		(pad "T1" smd circle
			(at -8.400034 3.599942 270)
			(size 0.3556 0.3556)
			(layers "F.Cu" "F.Mask" "F.Paste")
			(net "TP_BMC_GPIOL1")
		)
		(pad "T2" smd circle
			(at -7.599934 3.599942 270)
			(size 0.3556 0.3556)
			(layers "F.Cu" "F.Mask" "F.Paste")
			(net "TP_BMC_GPIOL0")
		)
		(pad "T3" smd circle
			(at -6.800088 3.599942 270)
			(size 0.3556 0.3556)
			(layers "F.Cu" "F.Mask" "F.Paste")
			(net "IOM_TYPE3")
		)
		(pad "T4" smd circle
			(at -5.999988 3.599942 270)
			(size 0.3556 0.3556)
			(layers "F.Cu" "F.Mask" "F.Paste")
			(net "TP_BMC_GPION7")
		)
		(pad "T5" smd circle
			(at -5.199888 3.599942 270)
			(size 0.3556 0.3556)
			(layers "F.Cu" "F.Mask" "F.Paste")
			(net "UART_EXP_BMC_TX_R")
		)
		(pad "T6" smd circle
			(at -4.400042 3.599942 270)
			(size 0.3556 0.3556)
			(layers "F.Cu" "F.Mask" "F.Paste")
			(net "GND")
		)
		(pad "T7" smd circle
			(at -3.599942 3.599942 270)
			(size 0.3556 0.3556)
			(layers "F.Cu" "F.Mask" "F.Paste")
			(net "GND")
		)
		(pad "T8" smd circle
			(at -2.800096 3.599942 270)
			(size 0.3556 0.3556)
			(layers "F.Cu" "F.Mask" "F.Paste")
			(net "P1V2_STBY")
		)
		(pad "T9" smd circle
			(at -1.999996 3.599942 270)
			(size 0.3556 0.3556)
			(layers "F.Cu" "F.Mask" "F.Paste")
			(net "DDR_VREF")
		)
		(pad "T10" smd circle
			(at -1.199896 3.599942 270)
			(size 0.3556 0.3556)
			(layers "F.Cu" "F.Mask" "F.Paste")
			(net "P1V2_STBY")
		)
		(pad "T11" smd circle
			(at -0.40005 3.599942 270)
			(size 0.3556 0.3556)
			(layers "F.Cu" "F.Mask" "F.Paste")
			(net "MPLLAV33")
		)
		(pad "T12" smd circle
			(at 0.40005 3.599942 270)
			(size 0.3556 0.3556)
			(layers "F.Cu" "F.Mask" "F.Paste")
			(net "P1V2_STBY")
		)
		(pad "T13" smd circle
			(at 1.199896 3.599942 270)
			(size 0.3556 0.3556)
			(layers "F.Cu" "F.Mask" "F.Paste")
			(net "P1V2_STBY")
		)
		(pad "T14" smd circle
			(at 1.999996 3.599942 270)
			(size 0.3556 0.3556)
			(layers "F.Cu" "F.Mask" "F.Paste")
			(net "P1V2_STBY")
		)
		(pad "T15" smd circle
			(at 2.800096 3.599942 270)
			(size 0.3556 0.3556)
			(layers "F.Cu" "F.Mask" "F.Paste")
			(net "P3V3_STBY")
		)
		(pad "T16" smd circle
			(at 3.599942 3.599942 270)
			(size 0.3556 0.3556)
			(layers "F.Cu" "F.Mask" "F.Paste")
			(net "GND")
		)
		(pad "T17" smd circle
			(at 4.400042 3.599942 270)
			(size 0.3556 0.3556)
			(layers "F.Cu" "F.Mask" "F.Paste")
			(net "TP_BMC_GPIOR2")
		)
		(pad "T18" smd circle
			(at 5.199888 3.599942 270)
			(size 0.3556 0.3556)
			(layers "F.Cu" "F.Mask" "F.Paste")
			(net "BMC_SPI_MISO")
		)
		(pad "T19" smd circle
			(at 5.999988 3.599942 270)
			(size 0.3556 0.3556)
			(layers "F.Cu" "F.Mask" "F.Paste")
			(net "TP_BMC_GPIOR1")
		)
		(pad "T20" smd circle
			(at 6.800088 3.599942 270)
			(size 0.3556 0.3556)
			(layers "F.Cu" "F.Mask" "F.Paste")
			(net "Net_98")
		)
		(pad "T21" smd circle
			(at 7.599934 3.599942 270)
			(size 0.3556 0.3556)
			(layers "F.Cu" "F.Mask" "F.Paste")
			(net "IOM_FULL_PGOOD")
		)
		(pad "T22" smd circle
			(at 8.400034 3.599942 270)
			(size 0.3556 0.3556)
			(layers "F.Cu" "F.Mask" "F.Paste")
			(net "BMC_SELF_HW_RST")
		)
		(pad "U1" smd circle
			(at -8.400034 4.400042 270)
			(size 0.3556 0.3556)
			(layers "F.Cu" "F.Mask" "F.Paste")
			(net "TP_BMC_GPIOL2")
		)
		(pad "U2" smd circle
			(at -7.599934 4.400042 270)
			(size 0.3556 0.3556)
			(layers "F.Cu" "F.Mask" "F.Paste")
			(net "TP_BMC_GPIOL3")
		)
		(pad "U3" smd circle
			(at -6.800088 4.400042 270)
			(size 0.3556 0.3556)
			(layers "F.Cu" "F.Mask" "F.Paste")
			(net "TP_BMC_GPION3")
		)
		(pad "U4" smd circle
			(at -5.999988 4.400042 270)
			(size 0.3556 0.3556)
			(layers "F.Cu" "F.Mask" "F.Paste")
			(net "BMC_LOC_HB")
		)
		(pad "U5" smd circle
			(at -5.199888 4.400042 270)
			(size 0.3556 0.3556)
			(layers "F.Cu" "F.Mask" "F.Paste")
			(net "BMC_RMT_HB")
		)
		(pad "U6" smd circle
			(at -4.400042 4.400042 270)
			(size 0.3556 0.3556)
			(layers "F.Cu" "F.Mask" "F.Paste")
			(net "GND")
		)
		(pad "U7" smd circle
			(at -3.599942 4.400042 270)
			(size 0.3556 0.3556)
			(layers "F.Cu" "F.Mask" "F.Paste")
			(net "MEMDQ_15")
		)
		(pad "U8" smd circle
			(at -2.800096 4.400042 270)
			(size 0.3556 0.3556)
			(layers "F.Cu" "F.Mask" "F.Paste")
			(net "MEMDM_0")
		)
		(pad "U9" smd circle
			(at -1.999996 4.400042 270)
			(size 0.3556 0.3556)
			(layers "F.Cu" "F.Mask" "F.Paste")
			(net "MEMDQ_4")
		)
		(pad "U10" smd circle
			(at -1.199896 4.400042 270)
			(size 0.3556 0.3556)
			(layers "F.Cu" "F.Mask" "F.Paste")
			(net "MEMDQ_0")
		)
		(pad "U11" smd circle
			(at -0.40005 4.400042 270)
			(size 0.3556 0.3556)
			(layers "F.Cu" "F.Mask" "F.Paste")
			(net "GND")
		)
		(pad "U12" smd circle
			(at 0.40005 4.400042 270)
			(size 0.3556 0.3556)
			(layers "F.Cu" "F.Mask" "F.Paste")
			(net "MEMBA_0")
		)
		(pad "U13" smd circle
			(at 1.199896 4.400042 270)
			(size 0.3556 0.3556)
			(layers "F.Cu" "F.Mask" "F.Paste")
			(net "MEMA_10")
		)
		(pad "U14" smd circle
			(at 1.999996 4.400042 270)
			(size 0.3556 0.3556)
			(layers "F.Cu" "F.Mask" "F.Paste")
			(net "MEMA_3")
		)
		(pad "U15" smd circle
			(at 2.800096 4.400042 270)
			(size 0.3556 0.3556)
			(layers "F.Cu" "F.Mask" "F.Paste")
			(net "Net_654")
		)
		(pad "U16" smd circle
			(at 3.599942 4.400042 270)
			(size 0.3556 0.3556)
			(layers "F.Cu" "F.Mask" "F.Paste")
			(net "DDR4_ALERT")
		)
		(pad "U17" smd circle
			(at 4.400042 4.400042 270)
			(size 0.3556 0.3556)
			(layers "F.Cu" "F.Mask" "F.Paste")
			(net "BMC_SPI_MOSI")
		)
		(pad "U18" smd circle
			(at 5.199888 4.400042 270)
			(size 0.3556 0.3556)
			(layers "F.Cu" "F.Mask" "F.Paste")
			(net "BMC0_SRST_N")
		)
		(pad "U19" smd circle
			(at 5.999988 4.400042 270)
			(size 0.3556 0.3556)
			(layers "F.Cu" "F.Mask" "F.Paste")
			(net "BMC_UART_SEL_OUT")
		)
		(pad "U20" smd circle
			(at 6.800088 4.400042 270)
			(size 0.3556 0.3556)
			(layers "F.Cu" "F.Mask" "F.Paste")
			(net "BMC_GPIOS6")
		)
		(pad "U21" smd circle
			(at 7.599934 4.400042 270)
			(size 0.3556 0.3556)
			(layers "F.Cu" "F.Mask" "F.Paste")
			(net "BMC_GPIOZ4")
		)
		(pad "U22" smd circle
			(at 8.400034 4.400042 270)
			(size 0.3556 0.3556)
			(layers "F.Cu" "F.Mask" "F.Paste")
			(net "Net_22")
		)
		(pad "V1" smd circle
			(at -8.400034 5.199888 270)
			(size 0.3556 0.3556)
			(layers "F.Cu" "F.Mask" "F.Paste")
			(net "UART_BMC_COMP_IN_RX")
		)
		(pad "V2" smd circle
			(at -7.599934 5.199888 270)
			(size 0.3556 0.3556)
			(layers "F.Cu" "F.Mask" "F.Paste")
			(net "FAN_PWM0_BMC")
		)
		(pad "V3" smd circle
			(at -6.800088 5.199888 270)
			(size 0.3556 0.3556)
			(layers "F.Cu" "F.Mask" "F.Paste")
			(net "TP_BMC_GPION2")
		)
		(pad "V4" smd circle
			(at -5.999988 5.199888 270)
			(size 0.3556 0.3556)
			(layers "F.Cu" "F.Mask" "F.Paste")
			(net "DEBUG_GPIO_BMC_R_6")
		)
		(pad "V5" smd circle
			(at -5.199888 5.199888 270)
			(size 0.3556 0.3556)
			(layers "F.Cu" "F.Mask" "F.Paste")
			(net "FLA0_WP_N_R")
		)
		(pad "V6" smd circle
			(at -4.400042 5.199888 270)
			(size 0.3556 0.3556)
			(layers "F.Cu" "F.Mask" "F.Paste")
			(net "DEBUG_GPIO_BMC_R_5")
		)
		(pad "V7" smd circle
			(at -3.599942 5.199888 270)
			(size 0.3556 0.3556)
			(layers "F.Cu" "F.Mask" "F.Paste")
			(net "MEMDQ_14")
		)
		(pad "V8" smd circle
			(at -2.800096 5.199888 270)
			(size 0.3556 0.3556)
			(layers "F.Cu" "F.Mask" "F.Paste")
			(net "GND")
		)
		(pad "V9" smd circle
			(at -1.999996 5.199888 270)
			(size 0.3556 0.3556)
			(layers "F.Cu" "F.Mask" "F.Paste")
			(net "MEMDQ_7")
		)
		(pad "V10" smd circle
			(at -1.199896 5.199888 270)
			(size 0.3556 0.3556)
			(layers "F.Cu" "F.Mask" "F.Paste")
			(net "GND")
		)
		(pad "V11" smd circle
			(at -0.40005 5.199888 270)
			(size 0.3556 0.3556)
			(layers "F.Cu" "F.Mask" "F.Paste")
			(net "MEMODT")
		)
		(pad "V12" smd circle
			(at 0.40005 5.199888 270)
			(size 0.3556 0.3556)
			(layers "F.Cu" "F.Mask" "F.Paste")
			(net "GND")
		)
		(pad "V13" smd circle
			(at 1.199896 5.199888 270)
			(size 0.3556 0.3556)
			(layers "F.Cu" "F.Mask" "F.Paste")
			(net "MEMA_0")
		)
		(pad "V14" smd circle
			(at 1.999996 5.199888 270)
			(size 0.3556 0.3556)
			(layers "F.Cu" "F.Mask" "F.Paste")
			(net "GND")
		)
		(pad "V15" smd circle
			(at 2.800096 5.199888 270)
			(size 0.3556 0.3556)
			(layers "F.Cu" "F.Mask" "F.Paste")
			(net "MEMA_5")
		)
		(pad "V16" smd circle
			(at 3.599942 5.199888 270)
			(size 0.3556 0.3556)
			(layers "F.Cu" "F.Mask" "F.Paste")
			(net "GND")
		)
		(pad "V17" smd circle
			(at 4.400042 5.199888 270)
			(size 0.3556 0.3556)
			(layers "F.Cu" "F.Mask" "F.Paste")
			(net "P1V15_STBY")
		)
		(pad "V18" smd circle
			(at 5.199888 5.199888 270)
			(size 0.3556 0.3556)
			(layers "F.Cu" "F.Mask" "F.Paste")
			(net "BMC_EXTRST_N")
		)
		(pad "V19" smd circle
			(at 5.999988 5.199888 270)
			(size 0.3556 0.3556)
			(layers "F.Cu" "F.Mask" "F.Paste")
			(net "TP_BMC_GPIOR5")
		)
		(pad "V20" smd circle
			(at 6.800088 5.199888 270)
			(size 0.3556 0.3556)
			(layers "F.Cu" "F.Mask" "F.Paste")
			(net "EXP_UART_EN")
		)
		(pad "V21" smd circle
			(at 7.599934 5.199888 270)
			(size 0.3556 0.3556)
			(layers "F.Cu" "F.Mask" "F.Paste")
			(net "CONN_A_PRSNTA")
		)
		(pad "V22" smd circle
			(at 8.400034 5.199888 270)
			(size 0.3556 0.3556)
			(layers "F.Cu" "F.Mask" "F.Paste")
			(net "BMC_GPIOZ6")
		)
		(pad "W1" smd circle
			(at -8.400034 5.999988 270)
			(size 0.3556 0.3556)
			(layers "F.Cu" "F.Mask" "F.Paste")
			(net "UART_COMP_OUT_TX_R")
		)
		(pad "W2" smd circle
			(at -7.599934 5.999988 270)
			(size 0.3556 0.3556)
			(layers "F.Cu" "F.Mask" "F.Paste")
			(net "FAN_PWM1_BMC")
		)
		(pad "W3" smd circle
			(at -6.800088 5.999988 270)
			(size 0.3556 0.3556)
			(layers "F.Cu" "F.Mask" "F.Paste")
			(net "TP_BMC_GPION4")
		)
		(pad "W4" smd circle
			(at -5.999988 5.999988 270)
			(size 0.3556 0.3556)
			(layers "F.Cu" "F.Mask" "F.Paste")
			(net "COMP_PWR_EN_R")
		)
		(pad "W5" smd circle
			(at -5.199888 5.999988 270)
			(size 0.3556 0.3556)
			(layers "F.Cu" "F.Mask" "F.Paste")
			(net "Net_134")
		)
		(pad "W6" smd circle
			(at -4.400042 5.999988 270)
			(size 0.3556 0.3556)
			(layers "F.Cu" "F.Mask" "F.Paste")
			(net "DEBUG_GPIO_BMC_R_4")
		)
		(pad "W7" smd circle
			(at -3.599942 5.999988 270)
			(size 0.3556 0.3556)
			(layers "F.Cu" "F.Mask" "F.Paste")
			(net "MEMDQ_13")
		)
		(pad "W8" smd circle
			(at -2.800096 5.999988 270)
			(size 0.3556 0.3556)
			(layers "F.Cu" "F.Mask" "F.Paste")
			(net "MEMDQ_11")
		)
		(pad "W9" smd circle
			(at -1.999996 5.999988 270)
			(size 0.3556 0.3556)
			(layers "F.Cu" "F.Mask" "F.Paste")
			(net "MEMDQ_6")
		)
		(pad "W10" smd circle
			(at -1.199896 5.999988 270)
			(size 0.3556 0.3556)
			(layers "F.Cu" "F.Mask" "F.Paste")
			(net "MEMDQ_1")
		)
		(pad "W11" smd circle
			(at -0.40005 5.999988 270)
			(size 0.3556 0.3556)
			(layers "F.Cu" "F.Mask" "F.Paste")
			(net "MIOZ")
		)
		(pad "W12" smd circle
			(at 0.40005 5.999988 270)
			(size 0.3556 0.3556)
			(layers "F.Cu" "F.Mask" "F.Paste")
			(net "MEMRASN")
		)
		(pad "W13" smd circle
			(at 1.199896 5.999988 270)
			(size 0.3556 0.3556)
			(layers "F.Cu" "F.Mask" "F.Paste")
			(net "MEMBG_0")
		)
		(pad "W14" smd circle
			(at 1.999996 5.999988 270)
			(size 0.3556 0.3556)
			(layers "F.Cu" "F.Mask" "F.Paste")
			(net "MEMA_2")
		)
		(pad "W15" smd circle
			(at 2.800096 5.999988 270)
			(size 0.3556 0.3556)
			(layers "F.Cu" "F.Mask" "F.Paste")
			(net "MEMA_4")
		)
		(pad "W16" smd circle
			(at 3.599942 5.999988 270)
			(size 0.3556 0.3556)
			(layers "F.Cu" "F.Mask" "F.Paste")
			(net "MEMA_8")
		)
		(pad "W17" smd circle
			(at 4.400042 5.999988 270)
			(size 0.3556 0.3556)
			(layers "F.Cu" "F.Mask" "F.Paste")
			(net "MPLLAV33")
		)
		(pad "W18" smd circle
			(at 5.199888 5.999988 270)
			(size 0.3556 0.3556)
			(layers "F.Cu" "F.Mask" "F.Paste")
			(net "CLKIN_24M_BMC")
		)
		(pad "W19" smd circle
			(at 5.999988 5.999988 270)
			(size 0.3556 0.3556)
			(layers "F.Cu" "F.Mask" "F.Paste")
			(net "TP_BMC_GPIOR4")
		)
		(pad "W20" smd circle
			(at 6.800088 5.999988 270)
			(size 0.3556 0.3556)
			(layers "F.Cu" "F.Mask" "F.Paste")
			(net "BMC_GPIOS5")
		)
		(pad "W21" smd circle
			(at 7.599934 5.999988 270)
			(size 0.3556 0.3556)
			(layers "F.Cu" "F.Mask" "F.Paste")
			(net "BMC_GPIOZ7")
		)
		(pad "W22" smd circle
			(at 8.400034 5.999988 270)
			(size 0.3556 0.3556)
			(layers "F.Cu" "F.Mask" "F.Paste")
			(net "BMC_GPIOZ5")
		)
		(pad "Y1" smd circle
			(at -8.400034 6.800088 270)
			(size 0.4064 0.4064)
			(layers "F.Cu" "F.Mask" "F.Paste")
			(net "Net_282")
		)
		(pad "Y2" smd circle
			(at -7.599934 6.800088 270)
			(size 0.4064 0.4064)
			(layers "F.Cu" "F.Mask" "F.Paste")
			(net "Net_285")
		)
		(pad "Y3" smd circle
			(at -6.800088 6.800088 270)
			(size 0.4064 0.4064)
			(layers "F.Cu" "F.Mask" "F.Paste")
			(net "TP_BMC_GPION6")
		)
		(pad "Y4" smd circle
			(at -5.999988 6.800088 270)
			(size 0.3556 0.3556)
			(layers "F.Cu" "F.Mask" "F.Paste")
			(net "SCC_B_HB_IN_R")
		)
		(pad "Y5" smd circle
			(at -5.199888 6.800088 270)
			(size 0.3556 0.3556)
			(layers "F.Cu" "F.Mask" "F.Paste")
			(net "DEBUG_GPIO_BMC_R_3")
		)
		(pad "Y6" smd circle
			(at -4.400042 6.800088 270)
			(size 0.3556 0.3556)
			(layers "F.Cu" "F.Mask" "F.Paste")
			(net "DEBUG_GPIO_BMC_R_2")
		)
		(pad "Y7" smd circle
			(at -3.599942 6.800088 270)
			(size 0.3556 0.3556)
			(layers "F.Cu" "F.Mask" "F.Paste")
			(net "MEMDQ_10")
		)
		(pad "Y8" smd circle
			(at -2.800096 6.800088 270)
			(size 0.3556 0.3556)
			(layers "F.Cu" "F.Mask" "F.Paste")
			(net "MEMDQ_9")
		)
		(pad "Y9" smd circle
			(at -1.999996 6.800088 270)
			(size 0.3556 0.3556)
			(layers "F.Cu" "F.Mask" "F.Paste")
			(net "MEMDQ_5")
		)
		(pad "Y10" smd circle
			(at -1.199896 6.800088 270)
			(size 0.3556 0.3556)
			(layers "F.Cu" "F.Mask" "F.Paste")
			(net "MEMDQ_2")
		)
		(pad "Y11" smd circle
			(at -0.40005 6.800088 270)
			(size 0.3556 0.3556)
			(layers "F.Cu" "F.Mask" "F.Paste")
			(net "MEMCKE")
		)
		(pad "Y12" smd circle
			(at 0.40005 6.800088 270)
			(size 0.3556 0.3556)
			(layers "F.Cu" "F.Mask" "F.Paste")
			(net "MEMWEN")
		)
		(pad "Y13" smd circle
			(at 1.199896 6.800088 270)
			(size 0.3556 0.3556)
			(layers "F.Cu" "F.Mask" "F.Paste")
			(net "MEMBA_1")
		)
		(pad "Y14" smd circle
			(at 1.999996 6.800088 270)
			(size 0.3556 0.3556)
			(layers "F.Cu" "F.Mask" "F.Paste")
			(net "MEMA_12")
		)
		(pad "Y15" smd circle
			(at 2.800096 6.800088 270)
			(size 0.3556 0.3556)
			(layers "F.Cu" "F.Mask" "F.Paste")
			(net "DDR4_ACT")
		)
		(pad "Y16" smd circle
			(at 3.599942 6.800088 270)
			(size 0.3556 0.3556)
			(layers "F.Cu" "F.Mask" "F.Paste")
			(net "MEMA_9")
		)
		(pad "Y17" smd circle
			(at 4.400042 6.800088 270)
			(size 0.3556 0.3556)
			(layers "F.Cu" "F.Mask" "F.Paste")
			(net "MPLLAV33")
		)
		(pad "Y18" smd circle
			(at 5.199888 6.800088 270)
			(size 0.3556 0.3556)
			(layers "F.Cu" "F.Mask" "F.Paste")
			(net "BMC_HBLED")
		)
		(pad "Y19" smd circle
			(at 5.999988 6.800088 270)
			(size 0.3556 0.3556)
			(layers "F.Cu" "F.Mask" "F.Paste")
			(net "TP_BMC_GPIOR3")
		)
		(pad "Y20" smd circle
			(at 6.800088 6.800088 270)
			(size 0.4064 0.4064)
			(layers "F.Cu" "F.Mask" "F.Paste")
			(net "DEBUG_RST_BTN_N")
		)
		(pad "Y21" smd circle
			(at 7.599934 6.800088 270)
			(size 0.4064 0.4064)
			(layers "F.Cu" "F.Mask" "F.Paste")
			(net "Net_87")
		)
		(pad "Y22" smd circle
			(at 8.400034 6.800088 270)
			(size 0.4064 0.4064)
			(layers "F.Cu" "F.Mask" "F.Paste")
			(net "Net_21")
		)
	)
)
